# SCM (Grand Teton) — schematic netlist excerpt (pin names and nets, part order shuffled) for the footprints in the layout excerpt that follows; sources: Cadence DE-HDL packaged netlist, KiCad conversion of 12092022_DA0F0TMDCD0_F0T_Management_Board_D_brd_V3_OCP.brd

R562  Q_RES  33.2 1% CHIP  pkg 0402LF  page 21 : A = RST_SPI_BMC_FLASH_R1_N ; B = RST_SPI_FLASH_BUF_N
R734  Q_RES  0 5% CHIP  pkg 0402LF  page 50 : A = REAR_PWR_BTN_N ; B = FM_DEBUG_PWR_BTN_N

(kicad_pcb
	(version 20260206)
	(generator "pcbnew")
	(generator_version "10.0")
	(general
		(thickness 1.6)
		(legacy_teardrops no)
	)
	(paper "A4")
	(title_block
		(title "12092022_DA0F0TMDCD0_F0T_Management_Board_D_brd_V3_OCP.brd")
		(comment 1 "Grand Teton / footprints 461-462 of 1440")
	)
	(layers
		(0 "F.Cu" signal "TOP")
		(4 "In1.Cu" signal "GND")
		(6 "In2.Cu" signal "IN1")
		(8 "In3.Cu" signal "GND1")
		(10 "In4.Cu" signal "IN2")
		(12 "In5.Cu" signal "VCC")
		(14 "In6.Cu" signal "VCC1")
		(16 "In7.Cu" signal "IN3")
		(18 "In8.Cu" signal "GND2")
		(20 "In9.Cu" signal "IN4")
		(22 "In10.Cu" signal "GND3")
		(2 "B.Cu" signal "BOTTOM")
		(9 "F.Adhes" user "F.Adhesive")
		(11 "B.Adhes" user "B.Adhesive")
		(13 "F.Paste" user "Package Geometry/Pastemask Top")
		(15 "B.Paste" user "Package Geometry/Pastemask Bottom")
		(5 "F.SilkS" user "Ref Des/Silkscreen Top")
		(7 "B.SilkS" user "Ref Des/Silkscreen Bottom")
		(1 "F.Mask" user "Board Geometry/Soldermask Top")
		(3 "B.Mask" user "Board Geometry/Soldermask Bottom")
		(17 "Dwgs.User" user "User.Drawings")
		(19 "Cmts.User" user "User.Comments")
		(21 "Eco1.User" user "User.Eco1")
		(23 "Eco2.User" user "User.Eco2")
		(25 "Edge.Cuts" user "Board Geometry/Outline")
		(27 "Margin" user)
		(31 "F.CrtYd" user "Package Geometry/Place Bound Top")
		(29 "B.CrtYd" user "Package Geometry/Place Bound Bottom")
		(35 "F.Fab" user "Ref Des/Assembly Top")
		(33 "B.Fab" user "Ref Des/Assembly Bottom")
	)
	(footprint ""
		(layer "F.Cu")
		(at 13.262864 -8.857742)
		(property "Reference" "R734"
			(at 0 0 0)
			(layer "F.SilkS")
			(hide yes)
			(effects
				(font
					(size 1.27 1.27)
				)
			)
		)
		(property "Value" ""
			(at 0 0 0)
			(layer "F.Fab")
			(effects
				(font
					(size 1.27 1.27)
				)
			)
		)
		(duplicate_pad_numbers_are_jumpers no)
		(fp_line
			(start -0.7874 -0.4064)
			(end 0.7874 -0.4064)
			(stroke
				(width 0.1524)
				(type default)
			)
			(layer "F.SilkS")
		)
		(fp_line
			(start -0.7874 0.4064)
			(end -0.7874 -0.4064)
			(stroke
				(width 0.1524)
				(type default)
			)
			(layer "F.SilkS")
		)
		(fp_line
			(start 0.7874 -0.4064)
			(end 0.7874 0.4064)
			(stroke
				(width 0.1524)
				(type default)
			)
			(layer "F.SilkS")
		)
		(fp_line
			(start 0.7874 0.4064)
			(end -0.7874 0.4064)
			(stroke
				(width 0.1524)
				(type default)
			)
			(layer "F.SilkS")
		)
		(fp_line
			(start -0.67945 -0.305054)
			(end -0.12065 -0.305054)
			(stroke
				(width 0.1)
				(type default)
			)
			(layer "F.Fab")
		)
		(fp_line
			(start -0.67945 0.3048)
			(end -0.67945 -0.305054)
			(stroke
				(width 0.1)
				(type default)
			)
			(layer "F.Fab")
		)
		(fp_line
			(start -0.12065 -0.305054)
			(end -0.12065 -0.2794)
			(stroke
				(width 0.1)
				(type default)
			)
			(layer "F.Fab")
		)
		(fp_line
			(start -0.12065 -0.2794)
			(end 0.12065 -0.2794)
			(stroke
				(width 0.1)
				(type default)
			)
			(layer "F.Fab")
		)
		(fp_line
			(start -0.12065 0.2794)
			(end -0.12065 0.3048)
			(stroke
				(width 0.1)
				(type default)
			)
			(layer "F.Fab")
		)
		(fp_line
			(start -0.12065 0.3048)
			(end -0.67945 0.3048)
			(stroke
				(width 0.1)
				(type default)
			)
			(layer "F.Fab")
		)
		(fp_line
			(start 0.120396 0.2794)
			(end -0.12065 0.2794)
			(stroke
				(width 0.1)
				(type default)
			)
			(layer "F.Fab")
		)
		(fp_line
			(start 0.120396 0.3048)
			(end 0.120396 0.2794)
			(stroke
				(width 0.1)
				(type default)
			)
			(layer "F.Fab")
		)
		(fp_line
			(start 0.12065 -0.3048)
			(end 0.67945 -0.3048)
			(stroke
				(width 0.1)
				(type default)
			)
			(layer "F.Fab")
		)
		(fp_line
			(start 0.12065 -0.2794)
			(end 0.12065 -0.3048)
			(stroke
				(width 0.1)
				(type default)
			)
			(layer "F.Fab")
		)
		(fp_line
			(start 0.67945 -0.3048)
			(end 0.67945 0.3048)
			(stroke
				(width 0.1)
				(type default)
			)
			(layer "F.Fab")
		)
		(fp_line
			(start 0.67945 0.3048)
			(end 0.120396 0.3048)
			(stroke
				(width 0.1)
				(type default)
			)
			(layer "F.Fab")
		)
		(pad "1" smd circle
			(at -0.40005 0)
			(size 0 0)
			(layers "F.Cu" "F.Mask" "F.Paste")
			(net "REAR_PWR_BTN_N")
		)
		(pad "2" smd circle
			(at 0.40005 0)
			(size 0 0)
			(layers "F.Cu" "F.Mask" "F.Paste")
			(net "FM_DEBUG_PWR_BTN_N")
		)
	)
	(footprint ""
		(layer "F.Cu")
		(at 22.225 -68.834 -90)
		(property "Reference" "R562"
			(at 0 0 270)
			(layer "F.SilkS")
			(hide yes)
			(effects
				(font
					(size 1.27 1.27)
				)
			)
		)
		(property "Value" ""
			(at 0 0 270)
			(layer "F.Fab")
			(effects
				(font
					(size 1.27 1.27)
				)
			)
		)
		(duplicate_pad_numbers_are_jumpers no)
		(fp_line
			(start -0.7874 0.4064)
			(end -0.7874 -0.4064)
			(stroke
				(width 0.1524)
				(type default)
			)
			(layer "F.SilkS")
		)
		(fp_line
			(start 0.7874 0.4064)
			(end -0.7874 0.4064)
			(stroke
				(width 0.1524)
				(type default)
			)
			(layer "F.SilkS")
		)
		(fp_line
			(start -0.7874 -0.4064)
			(end 0.7874 -0.4064)
			(stroke
				(width 0.1524)
				(type default)
			)
			(layer "F.SilkS")
		)
		(fp_line
			(start 0.7874 -0.4064)
			(end 0.7874 0.4064)
			(stroke
				(width 0.1524)
				(type default)
			)
			(layer "F.SilkS")
		)
		(fp_line
			(start -0.67945 0.3048)
			(end -0.67945 -0.305054)
			(stroke
				(width 0.1)
				(type default)
			)
			(layer "F.Fab")
		)
		(fp_line
			(start -0.12065 0.3048)
			(end -0.67945 0.3048)
			(stroke
				(width 0.1)
				(type default)
			)
			(layer "F.Fab")
		)
		(fp_line
			(start 0.120396 0.3048)
			(end 0.120396 0.2794)
			(stroke
				(width 0.1)
				(type default)
			)
			(layer "F.Fab")
		)
		(fp_line
			(start 0.67945 0.3048)
			(end 0.120396 0.3048)
			(stroke
				(width 0.1)
				(type default)
			)
			(layer "F.Fab")
		)
		(fp_line
			(start -0.12065 0.2794)
			(end -0.12065 0.3048)
			(stroke
				(width 0.1)
				(type default)
			)
			(layer "F.Fab")
		)
		(fp_line
			(start 0.120396 0.2794)
			(end -0.12065 0.2794)
			(stroke
				(width 0.1)
				(type default)
			)
			(layer "F.Fab")
		)
		(fp_line
			(start -0.12065 -0.2794)
			(end 0.12065 -0.2794)
			(stroke
				(width 0.1)
				(type default)
			)
			(layer "F.Fab")
		)
		(fp_line
			(start 0.12065 -0.2794)
			(end 0.12065 -0.3048)
			(stroke
				(width 0.1)
				(type default)
			)
			(layer "F.Fab")
		)
		(fp_line
			(start 0.12065 -0.3048)
			(end 0.67945 -0.3048)
			(stroke
				(width 0.1)
				(type default)
			)
			(layer "F.Fab")
		)
		(fp_line
			(start 0.67945 -0.3048)
			(end 0.67945 0.3048)
			(stroke
				(width 0.1)
				(type default)
			)
			(layer "F.Fab")
		)
		(fp_line
			(start -0.67945 -0.305054)
			(end -0.12065 -0.305054)
			(stroke
				(width 0.1)
				(type default)
			)
			(layer "F.Fab")
		)
		(fp_line
			(start -0.12065 -0.305054)
			(end -0.12065 -0.2794)
			(stroke
				(width 0.1)
				(type default)
			)
			(layer "F.Fab")
		)
		(pad "1" smd circle
			(at -0.40005 0 270)
			(size 0 0)
			(layers "F.Cu" "F.Mask" "F.Paste")
			(net "RST_SPI_BMC_FLASH_R1_N")
		)
		(pad "2" smd circle
			(at 0.40005 0 270)
			(size 0 0)
			(layers "F.Cu" "F.Mask" "F.Paste")
			(net "RST_SPI_FLASH_BUF_N")
		)
	)
)
